# S9S_MB_2U (Grand Teton) — schematic netlist excerpt (pin names and nets, part order shuffled) for the footprints in the layout excerpt that follows; sources: Cadence DE-HDL packaged netlist, KiCad conversion of 03242023_DA0F0TMBIJ0_F0T_Motherboard_J_brd_V01_OCP.brd

R4046  Q_RES  33.2 1% CHIP  pkg 0402LF  page 225 : A = RST_CPU1_DRAM_AB_PLD_LVT3_R_N ; B = RST_CPU1_DRAM_AB_PLD_LVT3_N
R2830  Q_RES  100K 1% CHIP  pkg 0402LF  page 148 : A = P3V3_AUX ; B = BIC_MONITER

(kicad_pcb
	(version 20260206)
	(generator "pcbnew")
	(generator_version "10.0")
	(general
		(thickness 1.6)
		(legacy_teardrops no)
	)
	(paper "A4")
	(title_block
		(title "03242023_DA0F0TMBIJ0_F0T_Motherboard_J_brd_V01_OCP.brd")
		(comment 1 "Grand Teton / footprints 2803-2804 of 6105")
	)
	(layers
		(0 "F.Cu" signal "TOP")
		(4 "In1.Cu" signal "GND")
		(6 "In2.Cu" signal "IN1")
		(8 "In3.Cu" signal "GND1")
		(10 "In4.Cu" signal "IN2")
		(12 "In5.Cu" signal "GND2")
		(14 "In6.Cu" signal "IN3")
		(16 "In7.Cu" signal "GND3")
		(18 "In8.Cu" signal "VCC")
		(20 "In9.Cu" signal "VCC1")
		(22 "In10.Cu" signal "GND4")
		(24 "In11.Cu" signal "IN4")
		(26 "In12.Cu" signal "GND5")
		(28 "In13.Cu" signal "IN5")
		(30 "In14.Cu" signal "GND6")
		(32 "In15.Cu" signal "IN6")
		(34 "In16.Cu" signal "GND7")
		(2 "B.Cu" signal "BOTTOM")
		(9 "F.Adhes" user "F.Adhesive")
		(11 "B.Adhes" user "B.Adhesive")
		(13 "F.Paste" user "Package Geometry/Pastemask Top")
		(15 "B.Paste" user "Package Geometry/Pastemask Bottom")
		(5 "F.SilkS" user "Ref Des/Silkscreen Top")
		(7 "B.SilkS" user "Ref Des/Silkscreen Bottom")
		(1 "F.Mask" user "Board Geometry/Soldermask Top")
		(3 "B.Mask" user "Board Geometry/Soldermask Bottom")
		(17 "Dwgs.User" user "User.Drawings")
		(19 "Cmts.User" user "User.Comments")
		(21 "Eco1.User" user "User.Eco1")
		(23 "Eco2.User" user "User.Eco2")
		(25 "Edge.Cuts" user "Board Geometry/Outline")
		(27 "Margin" user)
		(31 "F.CrtYd" user "Package Geometry/Place Bound Top")
		(29 "B.CrtYd" user "Package Geometry/Place Bound Bottom")
		(35 "F.Fab" user "Ref Des/Assembly Top")
		(33 "B.Fab" user "Ref Des/Assembly Bottom")
	)
	(footprint ""
		(layer "F.Cu")
		(at 122.05208 -106.238548 -90)
		(property "Reference" "R4046"
			(at 0 0 270)
			(layer "F.SilkS")
			(hide yes)
			(effects
				(font
					(size 1.27 1.27)
				)
			)
		)
		(property "Value" ""
			(at 0 0 270)
			(layer "F.Fab")
			(effects
				(font
					(size 1.27 1.27)
				)
			)
		)
		(duplicate_pad_numbers_are_jumpers no)
		(fp_line
			(start -0.7874 0.4064)
			(end -0.7874 -0.4064)
			(stroke
				(width 0.1524)
				(type default)
			)
			(layer "F.SilkS")
		)
		(fp_line
			(start 0.7874 0.4064)
			(end -0.7874 0.4064)
			(stroke
				(width 0.1524)
				(type default)
			)
			(layer "F.SilkS")
		)
		(fp_line
			(start -0.7874 -0.4064)
			(end 0.7874 -0.4064)
			(stroke
				(width 0.1524)
				(type default)
			)
			(layer "F.SilkS")
		)
		(fp_line
			(start 0.7874 -0.4064)
			(end 0.7874 0.4064)
			(stroke
				(width 0.1524)
				(type default)
			)
			(layer "F.SilkS")
		)
		(fp_line
			(start -0.67945 0.3048)
			(end -0.67945 -0.305054)
			(stroke
				(width 0.1)
				(type default)
			)
			(layer "F.Fab")
		)
		(fp_line
			(start -0.12065 0.3048)
			(end -0.67945 0.3048)
			(stroke
				(width 0.1)
				(type default)
			)
			(layer "F.Fab")
		)
		(fp_line
			(start 0.120396 0.3048)
			(end 0.120396 0.2794)
			(stroke
				(width 0.1)
				(type default)
			)
			(layer "F.Fab")
		)
		(fp_line
			(start 0.67945 0.3048)
			(end 0.120396 0.3048)
			(stroke
				(width 0.1)
				(type default)
			)
			(layer "F.Fab")
		)
		(fp_line
			(start -0.12065 0.2794)
			(end -0.12065 0.3048)
			(stroke
				(width 0.1)
				(type default)
			)
			(layer "F.Fab")
		)
		(fp_line
			(start 0.120396 0.2794)
			(end -0.12065 0.2794)
			(stroke
				(width 0.1)
				(type default)
			)
			(layer "F.Fab")
		)
		(fp_line
			(start -0.12065 -0.2794)
			(end 0.12065 -0.2794)
			(stroke
				(width 0.1)
				(type default)
			)
			(layer "F.Fab")
		)
		(fp_line
			(start 0.12065 -0.2794)
			(end 0.12065 -0.3048)
			(stroke
				(width 0.1)
				(type default)
			)
			(layer "F.Fab")
		)
		(fp_line
			(start 0.12065 -0.3048)
			(end 0.67945 -0.3048)
			(stroke
				(width 0.1)
				(type default)
			)
			(layer "F.Fab")
		)
		(fp_line
			(start 0.67945 -0.3048)
			(end 0.67945 0.3048)
			(stroke
				(width 0.1)
				(type default)
			)
			(layer "F.Fab")
		)
		(fp_line
			(start -0.67945 -0.305054)
			(end -0.12065 -0.305054)
			(stroke
				(width 0.1)
				(type default)
			)
			(layer "F.Fab")
		)
		(fp_line
			(start -0.12065 -0.305054)
			(end -0.12065 -0.2794)
			(stroke
				(width 0.1)
				(type default)
			)
			(layer "F.Fab")
		)
		(pad "1" smd circle
			(at -0.40005 0 270)
			(size 0 0)
			(layers "F.Cu" "F.Mask" "F.Paste")
			(net "RST_CPU1_DRAM_AB_PLD_LVT3_R_N")
		)
		(pad "2" smd circle
			(at 0.40005 0 270)
			(size 0 0)
			(layers "F.Cu" "F.Mask" "F.Paste")
			(net "RST_CPU1_DRAM_AB_PLD_LVT3_N")
		)
	)
	(footprint ""
		(layer "F.Cu")
		(at 118.849902 -407.335228 180)
		(property "Reference" "R2830"
			(at 0 0 180)
			(layer "F.SilkS")
			(hide yes)
			(effects
				(font
					(size 1.27 1.27)
				)
			)
		)
		(property "Value" ""
			(at 0 0 180)
			(layer "F.Fab")
			(effects
				(font
					(size 1.27 1.27)
				)
			)
		)
		(duplicate_pad_numbers_are_jumpers no)
		(fp_line
			(start 0.7874 0.4064)
			(end -0.7874 0.4064)
			(stroke
				(width 0.1524)
				(type default)
			)
			(layer "F.SilkS")
		)
		(fp_line
			(start 0.7874 -0.4064)
			(end 0.7874 0.4064)
			(stroke
				(width 0.1524)
				(type default)
			)
			(layer "F.SilkS")
		)
		(fp_line
			(start -0.7874 0.4064)
			(end -0.7874 -0.4064)
			(stroke
				(width 0.1524)
				(type default)
			)
			(layer "F.SilkS")
		)
		(fp_line
			(start -0.7874 -0.4064)
			(end 0.7874 -0.4064)
			(stroke
				(width 0.1524)
				(type default)
			)
			(layer "F.SilkS")
		)
		(fp_line
			(start 0.67945 0.3048)
			(end 0.120396 0.3048)
			(stroke
				(width 0.1)
				(type default)
			)
			(layer "F.Fab")
		)
		(fp_line
			(start 0.67945 -0.3048)
			(end 0.67945 0.3048)
			(stroke
				(width 0.1)
				(type default)
			)
			(layer "F.Fab")
		)
		(fp_line
			(start 0.12065 -0.2794)
			(end 0.12065 -0.3048)
			(stroke
				(width 0.1)
				(type default)
			)
			(layer "F.Fab")
		)
		(fp_line
			(start 0.12065 -0.3048)
			(end 0.67945 -0.3048)
			(stroke
				(width 0.1)
				(type default)
			)
			(layer "F.Fab")
		)
		(fp_line
			(start 0.120396 0.3048)
			(end 0.120396 0.2794)
			(stroke
				(width 0.1)
				(type default)
			)
			(layer "F.Fab")
		)
		(fp_line
			(start 0.120396 0.2794)
			(end -0.12065 0.2794)
			(stroke
				(width 0.1)
				(type default)
			)
			(layer "F.Fab")
		)
		(fp_line
			(start -0.12065 0.3048)
			(end -0.67945 0.3048)
			(stroke
				(width 0.1)
				(type default)
			)
			(layer "F.Fab")
		)
		(fp_line
			(start -0.12065 0.2794)
			(end -0.12065 0.3048)
			(stroke
				(width 0.1)
				(type default)
			)
			(layer "F.Fab")
		)
		(fp_line
			(start -0.12065 -0.2794)
			(end 0.12065 -0.2794)
			(stroke
				(width 0.1)
				(type default)
			)
			(layer "F.Fab")
		)
		(fp_line
			(start -0.12065 -0.305054)
			(end -0.12065 -0.2794)
			(stroke
				(width 0.1)
				(type default)
			)
			(layer "F.Fab")
		)
		(fp_line
			(start -0.67945 0.3048)
			(end -0.67945 -0.305054)
			(stroke
				(width 0.1)
				(type default)
			)
			(layer "F.Fab")
		)
		(fp_line
			(start -0.67945 -0.305054)
			(end -0.12065 -0.305054)
			(stroke
				(width 0.1)
				(type default)
			)
			(layer "F.Fab")
		)
		(pad "1" smd circle
			(at -0.40005 0 180)
			(size 0 0)
			(layers "F.Cu" "F.Mask" "F.Paste")
			(net "P3V3_AUX")
		)
		(pad "2" smd circle
			(at 0.40005 0 180)
			(size 0 0)
			(layers "F.Cu" "F.Mask" "F.Paste")
			(net "BIC_MONITER")
		)
	)
)
